(kicad_pcb
	(version 20241229)
	(generator "pcbnew")
	(generator_version "9.0")
	(general
		(thickness 1.61)
		(legacy_teardrops no)
	)
	(paper "A3")
	(title_block
		(title "RDIMM DDR5 Tester")
		(date "2026-05-21")
		(rev "2.2.0")
		(company "Antmicro")
		(comment 9 "footprints 92-96 of 796")
	)
	(layers
		(0 "F.Cu" signal)
		(4 "In1.Cu" power)
		(6 "In2.Cu" mixed)
		(8 "In3.Cu" power)
		(10 "In4.Cu" mixed)
		(12 "In5.Cu" power)
		(14 "In6.Cu" mixed)
		(16 "In7.Cu" power)
		(18 "In8.Cu" power)
		(20 "In9.Cu" mixed)
		(22 "In10.Cu" power)
		(2 "B.Cu" signal)
		(9 "F.Adhes" user "F.Adhesive")
		(11 "B.Adhes" user "B.Adhesive")
		(13 "F.Paste" user)
		(15 "B.Paste" user)
		(5 "F.SilkS" user "F.Silkscreen")
		(7 "B.SilkS" user "B.Silkscreen")
		(1 "F.Mask" user)
		(3 "B.Mask" user)
		(17 "Dwgs.User" user "User.Drawings")
		(19 "Cmts.User" user "User.Comments")
		(21 "Eco1.User" user "User.Eco1")
		(23 "Eco2.User" user "User.Eco2")
		(25 "Edge.Cuts" user)
		(27 "Margin" user)
		(31 "F.CrtYd" user "F.Courtyard")
		(29 "B.CrtYd" user "B.Courtyard")
		(35 "F.Fab" user)
		(33 "B.Fab" user)
	)
	(footprint "antmicro-footprints:X2SON8_1.4x1x0.32mm_P0.35mm"
		(layer "F.Cu")
		(at 147.934499 160.284)
		(property "Reference" "U32"
			(at -0.834499 1.591 90)
			(layer "F.SilkS")
			(effects
				(font
					(size 0.7 0.7)
					(thickness 0.15)
				)
				(justify left bottom)
			)
		)
		(property "Value" "TXS0102DQER"
			(at 0 1.929 0)
			(layer "F.Fab")
			(effects
				(font
					(size 0.7 0.7)
					(thickness 0.15)
				)
				(justify left bottom)
			)
		)
		(property "Datasheet" "https://www.ti.com/lit/ds/symlink/txs0102.pdf?ts=1637914596981&ref_url=https%253A%252F%252Fwww.ti.com%252Fstore%252Fti%252Fen%252Fp%252Fproduct%252F%253Fp%253DTXS0102DCTR%2526keyMatch%253DTXS0102DCTR%2526tisearch%253Dsearch-everything%2526usecase%253DOPN"
			(at 0 0 0)
			(layer "F.Fab")
			(hide yes)
			(effects
				(font
					(size 1.27 1.27)
					(thickness 0.15)
				)
			)
		)
		(property "MPN" "TXS0102DQER"
			(at 0 0 0)
			(unlocked yes)
			(layer "F.Fab")
			(hide yes)
			(effects
				(font
					(size 1 1)
					(thickness 0.15)
				)
			)
		)
		(property "Manufacturer" "Texas Instruments"
			(at 0 0 0)
			(unlocked yes)
			(layer "F.Fab")
			(hide yes)
			(effects
				(font
					(size 1 1)
					(thickness 0.15)
				)
			)
		)
		(property "Author" "Antmicro"
			(at 0 0 0)
			(unlocked yes)
			(layer "F.Fab")
			(hide yes)
			(effects
				(font
					(size 1 1)
					(thickness 0.15)
				)
			)
		)
		(property "License" "Apache-2.0"
			(at 0 0 0)
			(unlocked yes)
			(layer "F.Fab")
			(hide yes)
			(effects
				(font
					(size 1 1)
					(thickness 0.15)
				)
			)
		)
		(sheetname "/Debug FTDI + VNA/")
		(sheetfile "debug-ftdi.kicad_sch")
		(attr smd)
		(fp_line
			(start -0.6 -0.801)
			(end -0.6 -0.7)
			(stroke
				(width 0.15)
				(type solid)
			)
			(layer "F.SilkS")
		)
		(fp_line
			(start -0.6 0.7)
			(end -0.6 0.801)
			(stroke
				(width 0.15)
				(type solid)
			)
			(layer "F.SilkS")
		)
		(fp_line
			(start -0.6 0.801)
			(end -0.5 0.801)
			(stroke
				(width 0.15)
				(type solid)
			)
			(layer "F.SilkS")
		)
		(fp_line
			(start -0.402 -0.801)
			(end -0.6 -0.801)
			(stroke
				(width 0.15)
				(type solid)
			)
			(layer "F.SilkS")
		)
		(fp_line
			(start 0.598 -0.801)
			(end 0.498 -0.801)
			(stroke
				(width 0.15)
				(type solid)
			)
			(layer "F.SilkS")
		)
		(fp_line
			(start 0.598 -0.7)
			(end 0.598 -0.801)
			(stroke
				(width 0.15)
				(type solid)
			)
			(layer "F.SilkS")
		)
		(fp_line
			(start 0.598 0.7)
			(end 0.598 0.801)
			(stroke
				(width 0.15)
				(type solid)
			)
			(layer "F.SilkS")
		)
		(fp_line
			(start 0.598 0.801)
			(end 0.498 0.801)
			(stroke
				(width 0.15)
				(type solid)
			)
			(layer "F.SilkS")
		)
		(fp_circle
			(center -0.81 -0.77)
			(end -0.81 -0.72)
			(stroke
				(width 0.15)
				(type solid)
			)
			(fill yes)
			(layer "F.SilkS")
		)
		(fp_rect
			(start 0.75 -0.925)
			(end -0.75 0.925)
			(stroke
				(width 0.05)
				(type solid)
			)
			(fill no)
			(layer "F.CrtYd")
		)
		(fp_line
			(start -0.5 -0.729)
			(end -0.5 0.719)
			(stroke
				(width 0.15)
				(type solid)
			)
			(layer "F.Fab")
		)
		(fp_line
			(start -0.5 -0.724)
			(end 0.498 -0.724)
			(stroke
				(width 0.15)
				(type solid)
			)
			(layer "F.Fab")
		)
		(fp_line
			(start -0.5 0.724)
			(end 0.498 0.724)
			(stroke
				(width 0.15)
				(type solid)
			)
			(layer "F.Fab")
		)
		(fp_line
			(start 0.498 -0.719)
			(end 0.498 0.719)
			(stroke
				(width 0.15)
				(type solid)
			)
			(layer "F.Fab")
		)
		(fp_text user "Author: Antmicro"
			(at -0.95 5.129 0)
			(layer "F.Fab")
			(effects
				(font
					(size 0.7 0.7)
					(thickness 0.15)
				)
				(justify left bottom)
			)
		)
		(fp_text user "License: Apache-2.0"
			(at -0.95 6.329 0)
			(layer "F.Fab")
			(effects
				(font
					(size 0.7 0.7)
					(thickness 0.15)
				)
				(justify left bottom)
			)
		)
		(fp_text user "${REFERENCE}"
			(at -0.95 3.929 0)
			(layer "F.Fab")
			(effects
				(font
					(size 0.7 0.7)
					(thickness 0.15)
				)
				(justify left bottom)
			)
		)
		(pad "1" smd rect
			(at -0.43 -0.526 270)
			(size 0.17 0.5)
			(layers "F.Cu" "F.Mask" "F.Paste")
			(net 6 "/Debug FTDI + VNA/FTDI_3V3")
			(pinfunction "VCCA")
			(pintype "power_in")
		)
		(pad "2" smd rect
			(at -0.43 -0.175 270)
			(size 0.17 0.5)
			(layers "F.Cu" "F.Mask" "F.Paste")
			(net 792 "/Debug FTDI + VNA/FTDI_UART1_RX")
			(pinfunction "A1")
			(pintype "bidirectional")
		)
		(pad "3" smd rect
			(at -0.43 0.175 270)
			(size 0.17 0.5)
			(layers "F.Cu" "F.Mask" "F.Paste")
			(net 791 "/Debug FTDI + VNA/FTDI_UART1_TX")
			(pinfunction "A2")
			(pintype "bidirectional")
		)
		(pad "4" smd rect
			(at -0.43 0.526 270)
			(size 0.17 0.5)
			(layers "F.Cu" "F.Mask" "F.Paste")
			(net 1 "GND")
			(pinfunction "GND")
			(pintype "power_in")
		)
		(pad "5" smd rect
			(at 0.43 0.526 270)
			(size 0.17 0.5)
			(layers "F.Cu" "F.Mask" "F.Paste")
			(net 6 "/Debug FTDI + VNA/FTDI_3V3")
			(pinfunction "OE")
			(pintype "tri_state")
		)
		(pad "6" smd rect
			(at 0.43 0.175 270)
			(size 0.17 0.5)
			(layers "F.Cu" "F.Mask" "F.Paste")
			(net 449 "Net-(U32-B2)")
			(pinfunction "B2")
			(pintype "bidirectional")
		)
		(pad "7" smd rect
			(at 0.43 -0.175 270)
			(size 0.17 0.5)
			(layers "F.Cu" "F.Mask" "F.Paste")
			(net 448 "Net-(U32-B1)")
			(pinfunction "B1")
			(pintype "bidirectional")
		)
		(pad "8" smd rect
			(at 0.43 -0.526 270)
			(size 0.17 0.5)
			(layers "F.Cu" "F.Mask" "F.Paste")
			(net 151 "+3V3")
			(pinfunction "VCCB")
			(pintype "power_in")
		)
	)
	(footprint "antmicro-footprints:R_0402_1005Metric"
		(layer "F.Cu")
		(at 124.681 168.3125 90)
		(descr "Resistor SMD 0402")
		(tags "resistor SMD 0402")
		(property "Reference" "R218"
			(at -3.825 0.619 90)
			(layer "F.SilkS")
			(effects
				(font
					(size 0.7 0.7)
					(thickness 0.15)
				)
				(justify left bottom)
			)
		)
		(property "Value" "R_64k9_0402"
			(at -1.011843 1.772047 90)
			(layer "F.Fab")
			(effects
				(font
					(size 0.7 0.7)
					(thickness 0.15)
				)
				(justify left bottom)
			)
		)
		(property "Datasheet" "https://www.bourns.com/docs/product-datasheets/cr.pdf"
			(at 0 0 90)
			(layer "F.Fab")
			(hide yes)
			(effects
				(font
					(size 1.27 1.27)
					(thickness 0.15)
				)
			)
		)
		(property "MPN" "CR0402-FX-6492GLF"
			(at 0 0 90)
			(unlocked yes)
			(layer "F.Fab")
			(hide yes)
			(effects
				(font
					(size 1 1)
					(thickness 0.15)
				)
			)
		)
		(property "Manufacturer" "Bourns"
			(at 0 0 90)
			(unlocked yes)
			(layer "F.Fab")
			(hide yes)
			(effects
				(font
					(size 1 1)
					(thickness 0.15)
				)
			)
		)
		(property "License" "Apache-2.0"
			(at 0 0 90)
			(unlocked yes)
			(layer "F.Fab")
			(hide yes)
			(effects
				(font
					(size 1 1)
					(thickness 0.15)
				)
			)
		)
		(property "Author" "Antmicro"
			(at 0 0 90)
			(unlocked yes)
			(layer "F.Fab")
			(hide yes)
			(effects
				(font
					(size 1 1)
					(thickness 0.15)
				)
			)
		)
		(property "Val" "64k9"
			(at 0 0 90)
			(unlocked yes)
			(layer "F.Fab")
			(hide yes)
			(effects
				(font
					(size 1 1)
					(thickness 0.15)
				)
			)
		)
		(property "Tolerance" "1%"
			(at 0 0 90)
			(unlocked yes)
			(layer "F.Fab")
			(hide yes)
			(effects
				(font
					(size 1 1)
					(thickness 0.15)
				)
			)
		)
		(sheetname "/HDMI + SD Card/")
		(sheetfile "hdmi-sd-card.kicad_sch")
		(attr smd)
		(fp_rect
			(start -0.925 -0.47)
			(end 0.925 0.47)
			(stroke
				(width 0.05)
				(type default)
			)
			(fill no)
			(layer "F.CrtYd")
		)
		(fp_rect
			(start -0.5 -0.25)
			(end 0.5 0.25)
			(stroke
				(width 0.15)
				(type solid)
			)
			(fill no)
			(layer "F.Fab")
		)
		(fp_text user "Author: Antmicro"
			(at -0.95 4.169 90)
			(layer "F.Fab")
			(effects
				(font
					(size 0.7 0.7)
					(thickness 0.15)
				)
				(justify left bottom)
			)
		)
		(fp_text user "License: Apache-2.0"
			(at -0.95 5.169 90)
			(layer "F.Fab")
			(effects
				(font
					(size 0.7 0.7)
					(thickness 0.15)
				)
				(justify left bottom)
			)
		)
		(fp_text user "${REFERENCE}"
			(at -0.95 3.168 90)
			(layer "F.Fab")
			(effects
				(font
					(size 0.7 0.7)
					(thickness 0.15)
				)
				(justify left bottom)
			)
		)
		(pad "1" smd roundrect
			(at -0.48 0 90)
			(size 0.59 0.64)
			(layers "F.Cu" "F.Mask" "F.Paste")
			(roundrect_rratio 0.25)
			(net 1 "GND")
			(pintype "passive")
		)
		(pad "2" smd roundrect
			(at 0.48 0 90)
			(size 0.59 0.64)
			(layers "F.Cu" "F.Mask" "F.Paste")
			(roundrect_rratio 0.25)
			(net 737 "/HDMI + SD Card/EQ_SEL")
			(pintype "passive")
		)
	)
	(footprint "antmicro-footprints:R_0402_1005Metric"
		(layer "F.Cu")
		(at 137.424499 183.264 90)
		(descr "Resistor SMD 0402")
		(tags "resistor SMD 0402")
		(property "Reference" "R65"
			(at -1.049516 -2.151301 90)
			(layer "F.SilkS")
			(effects
				(font
					(size 0.7 0.7)
					(thickness 0.15)
				)
				(justify left bottom)
			)
		)
		(property "Value" "R_330R_0402"
			(at -1.011843 1.772047 90)
			(layer "F.Fab")
			(effects
				(font
					(size 0.7 0.7)
					(thickness 0.15)
				)
				(justify left bottom)
			)
		)
		(property "Datasheet" "https://www.bourns.com/docs/product-datasheets/cr.pdf"
			(at 0 0 90)
			(layer "F.Fab")
			(hide yes)
			(effects
				(font
					(size 1.27 1.27)
					(thickness 0.15)
				)
			)
		)
		(property "Manufacturer" "Bourns"
			(at 0 0 90)
			(unlocked yes)
			(layer "F.Fab")
			(hide yes)
			(effects
				(font
					(size 1 1)
					(thickness 0.15)
				)
			)
		)
		(property "MPN" "CR0402-FX-3300GLF"
			(at 0 0 90)
			(unlocked yes)
			(layer "F.Fab")
			(hide yes)
			(effects
				(font
					(size 1 1)
					(thickness 0.15)
				)
			)
		)
		(property "Val" "330R"
			(at 0 0 90)
			(unlocked yes)
			(layer "F.Fab")
			(hide yes)
			(effects
				(font
					(size 1 1)
					(thickness 0.15)
				)
			)
		)
		(property "License" "Apache-2.0"
			(at 0 0 90)
			(unlocked yes)
			(layer "F.Fab")
			(hide yes)
			(effects
				(font
					(size 1 1)
					(thickness 0.15)
				)
			)
		)
		(property "Author" "Antmicro"
			(at 0 0 90)
			(unlocked yes)
			(layer "F.Fab")
			(hide yes)
			(effects
				(font
					(size 1 1)
					(thickness 0.15)
				)
			)
		)
		(property "Tolerance" "1%"
			(at 0 0 90)
			(unlocked yes)
			(layer "F.Fab")
			(hide yes)
			(effects
				(font
					(size 1 1)
					(thickness 0.15)
				)
			)
		)
		(sheetname "/Debug FTDI + VNA/")
		(sheetfile "debug-ftdi.kicad_sch")
		(attr smd)
		(fp_rect
			(start -0.925 -0.47)
			(end 0.925 0.47)
			(stroke
				(width 0.05)
				(type default)
			)
			(fill no)
			(layer "F.CrtYd")
		)
		(fp_rect
			(start -0.5 -0.25)
			(end 0.5 0.25)
			(stroke
				(width 0.15)
				(type solid)
			)
			(fill no)
			(layer "F.Fab")
		)
		(fp_text user "License: Apache-2.0"
			(at -0.95 5.169 90)
			(layer "F.Fab")
			(effects
				(font
					(size 0.7 0.7)
					(thickness 0.15)
				)
				(justify left bottom)
			)
		)
		(fp_text user "${REFERENCE}"
			(at -0.95 3.168 90)
			(layer "F.Fab")
			(effects
				(font
					(size 0.7 0.7)
					(thickness 0.15)
				)
				(justify left bottom)
			)
		)
		(fp_text user "Author: Antmicro"
			(at -0.95 4.169 90)
			(layer "F.Fab")
			(effects
				(font
					(size 0.7 0.7)
					(thickness 0.15)
				)
				(justify left bottom)
			)
		)
		(pad "1" smd roundrect
			(at -0.48 0 90)
			(size 0.59 0.64)
			(layers "F.Cu" "F.Mask" "F.Paste")
			(roundrect_rratio 0.25)
			(net 41 "Net-(D11-A)")
			(pintype "passive")
		)
		(pad "2" smd roundrect
			(at 0.48 0 90)
			(size 0.59 0.64)
			(layers "F.Cu" "F.Mask" "F.Paste")
			(roundrect_rratio 0.25)
			(net 444 "/Debug FTDI + VNA/LED_RX0")
			(pintype "passive")
		)
	)
	(footprint "antmicro-footprints:TP_SMD_1mm"
		(layer "F.Cu")
		(at 244.024499 170.549 180)
		(property "Reference" "TP14"
			(at 0 -0.731898 180)
			(layer "F.SilkS")
			(hide yes)
			(effects
				(font
					(size 0.7 0.7)
					(thickness 0.15)
				)
				(justify left bottom)
			)
		)
		(property "Value" "TP_1mm_SMD"
			(at 0 1.4 180)
			(layer "F.Fab")
			(effects
				(font
					(size 0.7 0.7)
					(thickness 0.15)
				)
				(justify left bottom)
			)
		)
		(property "MPN" ""
			(at 0 0 180)
			(unlocked yes)
			(layer "F.Fab")
			(hide yes)
			(effects
				(font
					(size 1 1)
					(thickness 0.15)
				)
			)
		)
		(property "Manufacturer" ""
			(at 0 0 180)
			(unlocked yes)
			(layer "F.Fab")
			(hide yes)
			(effects
				(font
					(size 1 1)
					(thickness 0.15)
				)
			)
		)
		(property "Author" "Antmicro"
			(at 0 0 180)
			(unlocked yes)
			(layer "F.Fab")
			(hide yes)
			(effects
				(font
					(size 1 1)
					(thickness 0.15)
				)
			)
		)
		(property "License" "Apache-2.0"
			(at 0 0 180)
			(unlocked yes)
			(layer "F.Fab")
			(hide yes)
			(effects
				(font
					(size 1 1)
					(thickness 0.15)
				)
			)
		)
		(sheetname "/Supply/DC-DC AUX, MGT/")
		(sheetfile "dc-dc-aux-mgt.kicad_sch")
		(attr exclude_from_pos_files)
		(fp_circle
			(center 0 0)
			(end 0.6 0)
			(stroke
				(width 0.05)
				(type default)
			)
			(fill no)
			(layer "F.CrtYd")
		)
		(fp_text user "${REFERENCE}"
			(at -0.5 2.8 180)
			(layer "F.Fab")
			(effects
				(font
					(size 0.7 0.7)
					(thickness 0.15)
				)
				(justify left bottom)
			)
		)
		(fp_text user "Author: Antmicro"
			(at -0.5 4 180)
			(layer "F.Fab")
			(effects
				(font
					(size 0.7 0.7)
					(thickness 0.15)
				)
				(justify left bottom)
			)
		)
		(fp_text user "License: Apache-2.0"
			(at -0.5 5.2 180)
			(layer "F.Fab")
			(effects
				(font
					(size 0.7 0.7)
					(thickness 0.15)
				)
				(justify left bottom)
			)
		)
		(pad "1" smd circle
			(at 0 0 180)
			(size 1 1)
			(layers "F.Cu" "F.Mask")
			(net 172 "+1V2_MGTAVTT")
			(pinfunction "1")
			(pintype "passive")
		)
	)
	(footprint "antmicro-footprints:SC70-3"
		(layer "F.Cu")
		(at 250.274499 135.149)
		(property "Reference" "Q16"
			(at 0.505501 1.091 90)
			(layer "F.SilkS")
			(effects
				(font
					(size 0.7 0.7)
					(thickness 0.15)
				)
				(justify left bottom)
			)
		)
		(property "Value" "BSS138PW"
			(at 0 2.3 0)
			(layer "F.Fab")
			(effects
				(font
					(size 0.7 0.7)
					(thickness 0.15)
				)
				(justify left bottom)
			)
		)
		(property "Datasheet" "https://assets.nexperia.com/documents/data-sheet/BSS138PW.pdf"
			(at 0 0 0)
			(layer "F.Fab")
			(hide yes)
			(effects
				(font
					(size 1.27 1.27)
					(thickness 0.15)
				)
			)
		)
		(property "MPN" "BSS138PW"
			(at 0 0 0)
			(unlocked yes)
			(layer "F.Fab")
			(hide yes)
			(effects
				(font
					(size 1 1)
					(thickness 0.15)
				)
			)
		)
		(property "Manufacturer" "Nexperia"
			(at 0 0 0)
			(unlocked yes)
			(layer "F.Fab")
			(hide yes)
			(effects
				(font
					(size 1 1)
					(thickness 0.15)
				)
			)
		)
		(property "Author" "Antmicro"
			(at 0 0 0)
			(unlocked yes)
			(layer "F.Fab")
			(hide yes)
			(effects
				(font
					(size 1 1)
					(thickness 0.15)
				)
			)
		)
		(property "License" "Apache-2.0"
			(at 0 0 0)
			(unlocked yes)
			(layer "F.Fab")
			(hide yes)
			(effects
				(font
					(size 1 1)
					(thickness 0.15)
				)
			)
		)
		(sheetname "/Supply/")
		(sheetfile "supply.kicad_sch")
		(attr smd)
		(fp_line
			(start -0.3 -1)
			(end 0.627 -0.999)
			(stroke
				(width 0.15)
				(type solid)
			)
			(layer "F.SilkS")
		)
		(fp_line
			(start -0.3 1)
			(end 0.627 1.001)
			(stroke
				(width 0.15)
				(type solid)
			)
			(layer "F.SilkS")
		)
		(fp_line
			(start 0.627 -0.6)
			(end 0.627 -0.999)
			(stroke
				(width 0.15)
				(type solid)
			)
			(layer "F.SilkS")
		)
		(fp_line
			(start 0.627 0.6)
			(end 0.627 1.001)
			(stroke
				(width 0.15)
				(type solid)
			)
			(layer "F.SilkS")
		)
		(fp_line
			(start -1.4 1)
			(end -1.4 -1)
			(stroke
				(width 0.05)
				(type solid)
			)
			(layer "F.CrtYd")
		)
		(fp_line
			(start -0.9 -1.3)
			(end -0.9 -1)
			(stroke
				(width 0.05)
				(type solid)
			)
			(layer "F.CrtYd")
		)
		(fp_line
			(start -0.9 -1.3)
			(end 0.9 -1.3)
			(stroke
				(width 0.05)
				(type solid)
			)
			(layer "F.CrtYd")
		)
		(fp_line
			(start -0.9 -1)
			(end -1.4 -1)
			(stroke
				(width 0.05)
				(type solid)
			)
			(layer "F.CrtYd")
		)
		(fp_line
			(start -0.9 1)
			(end -1.4 1)
			(stroke
				(width 0.05)
				(type solid)
			)
			(layer "F.CrtYd")
		)
		(fp_line
			(start -0.9 1.3)
			(end -0.9 1)
			(stroke
				(width 0.05)
				(type solid)
			)
			(layer "F.CrtYd")
		)
		(fp_line
			(start 0.9 -1.3)
			(end 0.9 -0.4)
			(stroke
				(width 0.05)
				(type solid)
			)
			(layer "F.CrtYd")
		)
		(fp_line
			(start 0.9 -0.4)
			(end 1.4 -0.4)
			(stroke
				(width 0.05)
				(type solid)
			)
			(layer "F.CrtYd")
		)
		(fp_line
			(start 0.9 0.4)
			(end 0.9 1.3)
			(stroke
				(width 0.05)
				(type solid)
			)
			(layer "F.CrtYd")
		)
		(fp_line
			(start 0.9 1.3)
			(end -0.9 1.3)
			(stroke
				(width 0.05)
				(type solid)
			)
			(layer "F.CrtYd")
		)
		(fp_line
			(start 1.4 -0.4)
			(end 1.4 0.4)
			(stroke
				(width 0.05)
				(type solid)
			)
			(layer "F.CrtYd")
		)
		(fp_line
			(start 1.4 0.4)
			(end 0.9 0.4)
			(stroke
				(width 0.05)
				(type solid)
			)
			(layer "F.CrtYd")
		)
		(fp_rect
			(start -0.623 -0.999)
			(end 0.627 1.001)
			(stroke
				(width 0.15)
				(type solid)
			)
			(fill no)
			(layer "F.Fab")
		)
		(fp_text user "${REFERENCE}"
			(at -1.45 4.783 0)
			(layer "F.Fab")
			(effects
				(font
					(size 0.7 0.7)
					(thickness 0.15)
				)
				(justify left bottom)
			)
		)
		(fp_text user "License: Apache-2.0"
			(at -1.45 6.782 0)
			(layer "F.Fab")
			(effects
				(font
					(size 0.7 0.7)
					(thickness 0.15)
				)
				(justify left bottom)
			)
		)
		(fp_text user "Author: Antmicro"
			(at -1.45 5.782 0)
			(layer "F.Fab")
			(effects
				(font
					(size 0.7 0.7)
					(thickness 0.15)
				)
				(justify left bottom)
			)
		)
		(pad "1" smd rect
			(at -1.051 -0.65 90)
			(size 0.6 0.6)
			(layers "F.Cu" "F.Mask" "F.Paste")
			(net 184 "FPGA_POWER_CYCLE")
			(pinfunction "G")
			(pintype "passive")
		)
		(pad "2" smd rect
			(at -1.051 0.65 90)
			(size 0.6 0.6)
			(layers "F.Cu" "F.Mask" "F.Paste")
			(net 1 "GND")
			(pinfunction "S")
			(pintype "passive")
		)
		(pad "3" smd rect
			(at 1.05 0 90)
			(size 0.6 0.6)
			(layers "F.Cu" "F.Mask" "F.Paste")
			(net 286 "Net-(Q16-D)")
			(pinfunction "D")
			(pintype "passive")
		)
	)
)
